# T6G (Grand Teton) — schematic netlist excerpt (pin names and nets, part order shuffled) for the footprints in the layout excerpt that follows; sources: Cadence DE-HDL packaged netlist, KiCad conversion of 04192023_DAF0TMB3IC0_F0TG_MB_C_brd_V02_OCP.brd

PQ14  MOSFET_N  BSS138K IC  pkg SMLF  page 200
  DRAIN  = PVDDIO_P0_EN_G
  GATE  = PVDDIO_P0_EN_R
  SOURCE  = GND

PC127_6  Q_CAP  0.1UF 25V 10% X7R  pkg 0402  page 213 : A = SW_P12V_AUX_PVDDCR_CPU0_P1_FLT ; B = GND
C1354  Q_CAP  0.1UF 25V 10% X7R  pkg 0402  page 164 : A = P3V3_AUX ; B = GND

(kicad_pcb
	(version 20260206)
	(generator "pcbnew")
	(generator_version "10.0")
	(general
		(thickness 1.6)
		(legacy_teardrops no)
	)
	(paper "A4")
	(title_block
		(title "04192023_DAF0TMB3IC0_F0TG_MB_C_brd_V02_OCP.brd")
		(comment 1 "Grand Teton / footprints 4136-4138 of 8354")
	)
	(layers
		(0 "F.Cu" signal "TOP")
		(4 "In1.Cu" signal "GND")
		(6 "In2.Cu" signal "IN1")
		(8 "In3.Cu" signal "GND1")
		(10 "In4.Cu" signal "IN2")
		(12 "In5.Cu" signal "GND2")
		(14 "In6.Cu" signal "IN3")
		(16 "In7.Cu" signal "GND3")
		(18 "In8.Cu" signal "VCC")
		(20 "In9.Cu" signal "VCC1")
		(22 "In10.Cu" signal "GND4")
		(24 "In11.Cu" signal "IN4")
		(26 "In12.Cu" signal "GND5")
		(28 "In13.Cu" signal "IN5")
		(30 "In14.Cu" signal "GND6")
		(32 "In15.Cu" signal "IN6")
		(34 "In16.Cu" signal "GND7")
		(2 "B.Cu" signal "BOTTOM")
		(9 "F.Adhes" user "F.Adhesive")
		(11 "B.Adhes" user "B.Adhesive")
		(13 "F.Paste" user "Package Geometry/Pastemask Top")
		(15 "B.Paste" user "Package Geometry/Pastemask Bottom")
		(5 "F.SilkS" user "Ref Des/Silkscreen Top")
		(7 "B.SilkS" user "Ref Des/Silkscreen Bottom")
		(1 "F.Mask" user "Board Geometry/Soldermask Top")
		(3 "B.Mask" user "Board Geometry/Soldermask Bottom")
		(17 "Dwgs.User" user "User.Drawings")
		(19 "Cmts.User" user "User.Comments")
		(21 "Eco1.User" user "User.Eco1")
		(23 "Eco2.User" user "User.Eco2")
		(25 "Edge.Cuts" user "Board Geometry/Outline")
		(27 "Margin" user)
		(31 "F.CrtYd" user "Package Geometry/Place Bound Top")
		(29 "B.CrtYd" user "Package Geometry/Place Bound Bottom")
		(35 "F.Fab" user "Ref Des/Assembly Top")
		(33 "B.Fab" user "Ref Des/Assembly Bottom")
	)
	(footprint ""
		(layer "F.Cu")
		(at 291.706046 -368.230658)
		(property "Reference" "PQ14"
			(at 0.935482 -4.364482 0)
			(unlocked yes)
			(layer "F.SilkS")
			(effects
				(font
					(size 0.7874 0.5842)
					(thickness 0.1524)
				)
			)
		)
		(property "Value" ""
			(at 0 0 0)
			(layer "F.Fab")
			(effects
				(font
					(size 1.27 1.27)
				)
			)
		)
		(duplicate_pad_numbers_are_jumpers no)
		(fp_line
			(start -1.949958 -1.610106)
			(end 1.949958 -1.610106)
			(stroke
				(width 0.1524)
				(type default)
			)
			(layer "F.SilkS")
		)
		(fp_line
			(start -1.949958 1.610106)
			(end -1.949958 -1.610106)
			(stroke
				(width 0.1524)
				(type default)
			)
			(layer "F.SilkS")
		)
		(fp_line
			(start 1.949958 -1.560068)
			(end 1.949958 1.610106)
			(stroke
				(width 0.1524)
				(type default)
			)
			(layer "F.SilkS")
		)
		(fp_line
			(start 1.949958 1.610106)
			(end -1.949958 1.610106)
			(stroke
				(width 0.1524)
				(type default)
			)
			(layer "F.SilkS")
		)
		(fp_line
			(start -0.750062 -1.560068)
			(end 0.750062 -1.560068)
			(stroke
				(width 0.1)
				(type default)
			)
			(layer "F.Fab")
		)
		(fp_line
			(start -0.750062 1.560068)
			(end -0.750062 -1.560068)
			(stroke
				(width 0.1)
				(type default)
			)
			(layer "F.Fab")
		)
		(fp_line
			(start 0.750062 -1.560068)
			(end 0.750062 1.560068)
			(stroke
				(width 0.1)
				(type default)
			)
			(layer "F.Fab")
		)
		(fp_line
			(start 0.750062 1.560068)
			(end -0.750062 1.560068)
			(stroke
				(width 0.1)
				(type default)
			)
			(layer "F.Fab")
		)
		(pad "D" smd rect
			(at 1.100074 0 270)
			(size 1.016 1.4224)
			(layers "F.Cu" "F.Mask" "F.Paste")
			(net "PVDDIO_P0_EN_G")
		)
		(pad "G" smd rect
			(at -1.100074 -0.94996 270)
			(size 1.016 1.4224)
			(layers "F.Cu" "F.Mask" "F.Paste")
			(net "PVDDIO_P0_EN_R")
		)
		(pad "S" smd rect
			(at -1.100074 0.94996 270)
			(size 1.016 1.4224)
			(layers "F.Cu" "F.Mask" "F.Paste")
			(net "GND")
		)
	)
	(footprint ""
		(layer "F.Cu")
		(at 63.405258 -162.790886)
		(property "Reference" "PC127_6"
			(at 0 0 0)
			(layer "F.SilkS")
			(hide yes)
			(effects
				(font
					(size 1.27 1.27)
				)
			)
		)
		(property "Value" ""
			(at 0 0 0)
			(layer "F.Fab")
			(effects
				(font
					(size 1.27 1.27)
				)
			)
		)
		(duplicate_pad_numbers_are_jumpers no)
		(fp_line
			(start -0.7874 -0.4064)
			(end 0.7874 -0.4064)
			(stroke
				(width 0.1524)
				(type default)
			)
			(layer "F.SilkS")
		)
		(fp_line
			(start -0.7874 0.4064)
			(end -0.7874 -0.4064)
			(stroke
				(width 0.1524)
				(type default)
			)
			(layer "F.SilkS")
		)
		(fp_line
			(start 0.7874 -0.4064)
			(end 0.7874 0.4064)
			(stroke
				(width 0.1524)
				(type default)
			)
			(layer "F.SilkS")
		)
		(fp_line
			(start 0.7874 0.4064)
			(end -0.7874 0.4064)
			(stroke
				(width 0.1524)
				(type default)
			)
			(layer "F.SilkS")
		)
		(fp_line
			(start -0.67945 -0.305054)
			(end -0.12065 -0.305054)
			(stroke
				(width 0.1)
				(type default)
			)
			(layer "F.Fab")
		)
		(fp_line
			(start -0.67945 0.3048)
			(end -0.67945 -0.305054)
			(stroke
				(width 0.1)
				(type default)
			)
			(layer "F.Fab")
		)
		(fp_line
			(start -0.12065 -0.305054)
			(end -0.12065 -0.2794)
			(stroke
				(width 0.1)
				(type default)
			)
			(layer "F.Fab")
		)
		(fp_line
			(start -0.12065 -0.2794)
			(end 0.12065 -0.2794)
			(stroke
				(width 0.1)
				(type default)
			)
			(layer "F.Fab")
		)
		(fp_line
			(start -0.12065 0.2794)
			(end -0.12065 0.3048)
			(stroke
				(width 0.1)
				(type default)
			)
			(layer "F.Fab")
		)
		(fp_line
			(start -0.12065 0.3048)
			(end -0.67945 0.3048)
			(stroke
				(width 0.1)
				(type default)
			)
			(layer "F.Fab")
		)
		(fp_line
			(start 0.120396 0.2794)
			(end -0.12065 0.2794)
			(stroke
				(width 0.1)
				(type default)
			)
			(layer "F.Fab")
		)
		(fp_line
			(start 0.120396 0.3048)
			(end 0.120396 0.2794)
			(stroke
				(width 0.1)
				(type default)
			)
			(layer "F.Fab")
		)
		(fp_line
			(start 0.12065 -0.3048)
			(end 0.67945 -0.3048)
			(stroke
				(width 0.1)
				(type default)
			)
			(layer "F.Fab")
		)
		(fp_line
			(start 0.12065 -0.2794)
			(end 0.12065 -0.3048)
			(stroke
				(width 0.1)
				(type default)
			)
			(layer "F.Fab")
		)
		(fp_line
			(start 0.67945 -0.3048)
			(end 0.67945 0.3048)
			(stroke
				(width 0.1)
				(type default)
			)
			(layer "F.Fab")
		)
		(fp_line
			(start 0.67945 0.3048)
			(end 0.120396 0.3048)
			(stroke
				(width 0.1)
				(type default)
			)
			(layer "F.Fab")
		)
		(pad "1" smd circle
			(at -0.40005 0)
			(size 0 0)
			(layers "F.Cu" "F.Mask" "F.Paste")
			(net "SW_P12V_AUX_PVDDCR_CPU0_P1_FLT")
		)
		(pad "2" smd circle
			(at 0.40005 0)
			(size 0 0)
			(layers "F.Cu" "F.Mask" "F.Paste")
			(net "GND")
		)
	)
	(footprint ""
		(layer "F.Cu")
		(at 370.139468 -32.573468)
		(property "Reference" "C1354"
			(at 0 0 0)
			(layer "F.SilkS")
			(hide yes)
			(effects
				(font
					(size 1.27 1.27)
				)
			)
		)
		(property "Value" ""
			(at 0 0 0)
			(layer "F.Fab")
			(effects
				(font
					(size 1.27 1.27)
				)
			)
		)
		(duplicate_pad_numbers_are_jumpers no)
		(fp_line
			(start -0.7874 -0.4064)
			(end 0.7874 -0.4064)
			(stroke
				(width 0.1524)
				(type default)
			)
			(layer "F.SilkS")
		)
		(fp_line
			(start -0.7874 0.4064)
			(end -0.7874 -0.4064)
			(stroke
				(width 0.1524)
				(type default)
			)
			(layer "F.SilkS")
		)
		(fp_line
			(start 0.7874 -0.4064)
			(end 0.7874 0.4064)
			(stroke
				(width 0.1524)
				(type default)
			)
			(layer "F.SilkS")
		)
		(fp_line
			(start 0.7874 0.4064)
			(end -0.7874 0.4064)
			(stroke
				(width 0.1524)
				(type default)
			)
			(layer "F.SilkS")
		)
		(fp_line
			(start -0.67945 -0.305054)
			(end -0.12065 -0.305054)
			(stroke
				(width 0.1)
				(type default)
			)
			(layer "F.Fab")
		)
		(fp_line
			(start -0.67945 0.3048)
			(end -0.67945 -0.305054)
			(stroke
				(width 0.1)
				(type default)
			)
			(layer "F.Fab")
		)
		(fp_line
			(start -0.12065 -0.305054)
			(end -0.12065 -0.2794)
			(stroke
				(width 0.1)
				(type default)
			)
			(layer "F.Fab")
		)
		(fp_line
			(start -0.12065 -0.2794)
			(end 0.12065 -0.2794)
			(stroke
				(width 0.1)
				(type default)
			)
			(layer "F.Fab")
		)
		(fp_line
			(start -0.12065 0.2794)
			(end -0.12065 0.3048)
			(stroke
				(width 0.1)
				(type default)
			)
			(layer "F.Fab")
		)
		(fp_line
			(start -0.12065 0.3048)
			(end -0.67945 0.3048)
			(stroke
				(width 0.1)
				(type default)
			)
			(layer "F.Fab")
		)
		(fp_line
			(start 0.120396 0.2794)
			(end -0.12065 0.2794)
			(stroke
				(width 0.1)
				(type default)
			)
			(layer "F.Fab")
		)
		(fp_line
			(start 0.120396 0.3048)
			(end 0.120396 0.2794)
			(stroke
				(width 0.1)
				(type default)
			)
			(layer "F.Fab")
		)
		(fp_line
			(start 0.12065 -0.3048)
			(end 0.67945 -0.3048)
			(stroke
				(width 0.1)
				(type default)
			)
			(layer "F.Fab")
		)
		(fp_line
			(start 0.12065 -0.2794)
			(end 0.12065 -0.3048)
			(stroke
				(width 0.1)
				(type default)
			)
			(layer "F.Fab")
		)
		(fp_line
			(start 0.67945 -0.3048)
			(end 0.67945 0.3048)
			(stroke
				(width 0.1)
				(type default)
			)
			(layer "F.Fab")
		)
		(fp_line
			(start 0.67945 0.3048)
			(end 0.120396 0.3048)
			(stroke
				(width 0.1)
				(type default)
			)
			(layer "F.Fab")
		)
		(pad "1" smd circle
			(at -0.40005 0)
			(size 0 0)
			(layers "F.Cu" "F.Mask" "F.Paste")
			(net "P3V3_AUX")
		)
		(pad "2" smd circle
			(at 0.40005 0)
			(size 0 0)
			(layers "F.Cu" "F.Mask" "F.Paste")
			(net "GND")
		)
	)
)
